(kicad_pcb
	(version 20260206)
	(generator "pcbnew")
	(generator_version "10.0")
	(general
		(thickness 1.6)
		(legacy_teardrops no)
	)
	(paper "A4")
	(title_block
		(title "04192023_DAF0TMB3IC0_F0TG_MB_C_brd_V02_OCP.brd")
		(comment 1 "Grand Teton / footprints 8210-8216 of 8354")
	)
	(layers
		(0 "F.Cu" signal "TOP")
		(4 "In1.Cu" signal "GND")
		(6 "In2.Cu" signal "IN1")
		(8 "In3.Cu" signal "GND1")
		(10 "In4.Cu" signal "IN2")
		(12 "In5.Cu" signal "GND2")
		(14 "In6.Cu" signal "IN3")
		(16 "In7.Cu" signal "GND3")
		(18 "In8.Cu" signal "VCC")
		(20 "In9.Cu" signal "VCC1")
		(22 "In10.Cu" signal "GND4")
		(24 "In11.Cu" signal "IN4")
		(26 "In12.Cu" signal "GND5")
		(28 "In13.Cu" signal "IN5")
		(30 "In14.Cu" signal "GND6")
		(32 "In15.Cu" signal "IN6")
		(34 "In16.Cu" signal "GND7")
		(2 "B.Cu" signal "BOTTOM")
		(9 "F.Adhes" user "F.Adhesive")
		(11 "B.Adhes" user "B.Adhesive")
		(13 "F.Paste" user "Package Geometry/Pastemask Top")
		(15 "B.Paste" user "Package Geometry/Pastemask Bottom")
		(5 "F.SilkS" user "Ref Des/Silkscreen Top")
		(7 "B.SilkS" user "Ref Des/Silkscreen Bottom")
		(1 "F.Mask" user "Board Geometry/Soldermask Top")
		(3 "B.Mask" user "Board Geometry/Soldermask Bottom")
		(17 "Dwgs.User" user "User.Drawings")
		(19 "Cmts.User" user "User.Comments")
		(21 "Eco1.User" user "User.Eco1")
		(23 "Eco2.User" user "User.Eco2")
		(25 "Edge.Cuts" user "Board Geometry/Outline")
		(27 "Margin" user)
		(31 "F.CrtYd" user "Package Geometry/Place Bound Top")
		(29 "B.CrtYd" user "Package Geometry/Place Bound Bottom")
		(35 "F.Fab" user "Ref Des/Assembly Top")
		(33 "B.Fab" user "Ref Des/Assembly Bottom")
	)
	(footprint ""
		(layer "B.Cu")
		(at 348.437454 -256.73431 180)
		(property "Reference" "C2619"
			(at 0 0 0)
			(layer "B.SilkS")
			(hide yes)
			(effects
				(font
					(size 1.27 1.27)
				)
				(justify mirror)
			)
		)
		(property "Value" ""
			(at 0 0 0)
			(layer "B.Fab")
			(effects
				(font
					(size 1.27 1.27)
				)
				(justify mirror)
			)
		)
		(duplicate_pad_numbers_are_jumpers no)
		(fp_line
			(start 0.7874 0.4064)
			(end 0.7874 -0.4064)
			(stroke
				(width 0.1524)
				(type default)
			)
			(layer "B.SilkS")
		)
		(fp_line
			(start 0.7874 -0.4064)
			(end -0.7874 -0.4064)
			(stroke
				(width 0.1524)
				(type default)
			)
			(layer "B.SilkS")
		)
		(fp_line
			(start -0.7874 0.4064)
			(end 0.7874 0.4064)
			(stroke
				(width 0.1524)
				(type default)
			)
			(layer "B.SilkS")
		)
		(fp_line
			(start -0.7874 -0.4064)
			(end -0.7874 0.4064)
			(stroke
				(width 0.1524)
				(type default)
			)
			(layer "B.SilkS")
		)
		(fp_line
			(start 0.67945 0.3048)
			(end 0.67945 -0.305054)
			(stroke
				(width 0.1)
				(type default)
			)
			(layer "B.Fab")
		)
		(fp_line
			(start 0.67945 -0.305054)
			(end 0.12065 -0.305054)
			(stroke
				(width 0.1)
				(type default)
			)
			(layer "B.Fab")
		)
		(fp_line
			(start 0.12065 0.3048)
			(end 0.67945 0.3048)
			(stroke
				(width 0.1)
				(type default)
			)
			(layer "B.Fab")
		)
		(fp_line
			(start 0.12065 0.2794)
			(end 0.12065 0.3048)
			(stroke
				(width 0.1)
				(type default)
			)
			(layer "B.Fab")
		)
		(fp_line
			(start 0.12065 -0.2794)
			(end -0.12065 -0.2794)
			(stroke
				(width 0.1)
				(type default)
			)
			(layer "B.Fab")
		)
		(fp_line
			(start 0.12065 -0.305054)
			(end 0.12065 -0.2794)
			(stroke
				(width 0.1)
				(type default)
			)
			(layer "B.Fab")
		)
		(fp_line
			(start -0.120396 0.3048)
			(end -0.120396 0.2794)
			(stroke
				(width 0.1)
				(type default)
			)
			(layer "B.Fab")
		)
		(fp_line
			(start -0.120396 0.2794)
			(end 0.12065 0.2794)
			(stroke
				(width 0.1)
				(type default)
			)
			(layer "B.Fab")
		)
		(fp_line
			(start -0.12065 -0.2794)
			(end -0.12065 -0.3048)
			(stroke
				(width 0.1)
				(type default)
			)
			(layer "B.Fab")
		)
		(fp_line
			(start -0.12065 -0.3048)
			(end -0.67945 -0.3048)
			(stroke
				(width 0.1)
				(type default)
			)
			(layer "B.Fab")
		)
		(fp_line
			(start -0.67945 0.3048)
			(end -0.120396 0.3048)
			(stroke
				(width 0.1)
				(type default)
			)
			(layer "B.Fab")
		)
		(fp_line
			(start -0.67945 -0.3048)
			(end -0.67945 0.3048)
			(stroke
				(width 0.1)
				(type default)
			)
			(layer "B.Fab")
		)
		(pad "1" smd circle
			(at 0.40005 0)
			(size 0 0)
			(layers "B.Cu" "B.Mask" "B.Paste")
			(net "PVDDIO_P0")
		)
		(pad "2" smd circle
			(at -0.40005 0)
			(size 0 0)
			(layers "B.Cu" "B.Mask" "B.Paste")
			(net "GND")
		)
	)
	(footprint ""
		(layer "B.Cu")
		(at 339.72881 -337.689698 -90)
		(property "Reference" "PR96"
			(at 0 0 90)
			(layer "B.SilkS")
			(hide yes)
			(effects
				(font
					(size 1.27 1.27)
				)
				(justify mirror)
			)
		)
		(property "Value" ""
			(at 0 0 90)
			(layer "B.Fab")
			(effects
				(font
					(size 1.27 1.27)
				)
				(justify mirror)
			)
		)
		(duplicate_pad_numbers_are_jumpers no)
		(fp_line
			(start -0.7874 0.4064)
			(end 0.7874 0.4064)
			(stroke
				(width 0.1524)
				(type default)
			)
			(layer "B.SilkS")
		)
		(fp_line
			(start 0.7874 0.4064)
			(end 0.7874 -0.4064)
			(stroke
				(width 0.1524)
				(type default)
			)
			(layer "B.SilkS")
		)
		(fp_line
			(start -0.7874 -0.4064)
			(end -0.7874 0.4064)
			(stroke
				(width 0.1524)
				(type default)
			)
			(layer "B.SilkS")
		)
		(fp_line
			(start 0.7874 -0.4064)
			(end -0.7874 -0.4064)
			(stroke
				(width 0.1524)
				(type default)
			)
			(layer "B.SilkS")
		)
		(fp_line
			(start -0.67945 0.3048)
			(end -0.120396 0.3048)
			(stroke
				(width 0.1)
				(type default)
			)
			(layer "B.Fab")
		)
		(fp_line
			(start -0.120396 0.3048)
			(end -0.120396 0.2794)
			(stroke
				(width 0.1)
				(type default)
			)
			(layer "B.Fab")
		)
		(fp_line
			(start 0.12065 0.3048)
			(end 0.67945 0.3048)
			(stroke
				(width 0.1)
				(type default)
			)
			(layer "B.Fab")
		)
		(fp_line
			(start 0.67945 0.3048)
			(end 0.67945 -0.305054)
			(stroke
				(width 0.1)
				(type default)
			)
			(layer "B.Fab")
		)
		(fp_line
			(start -0.120396 0.2794)
			(end 0.12065 0.2794)
			(stroke
				(width 0.1)
				(type default)
			)
			(layer "B.Fab")
		)
		(fp_line
			(start 0.12065 0.2794)
			(end 0.12065 0.3048)
			(stroke
				(width 0.1)
				(type default)
			)
			(layer "B.Fab")
		)
		(fp_line
			(start -0.12065 -0.2794)
			(end -0.12065 -0.3048)
			(stroke
				(width 0.1)
				(type default)
			)
			(layer "B.Fab")
		)
		(fp_line
			(start 0.12065 -0.2794)
			(end -0.12065 -0.2794)
			(stroke
				(width 0.1)
				(type default)
			)
			(layer "B.Fab")
		)
		(fp_line
			(start -0.67945 -0.3048)
			(end -0.67945 0.3048)
			(stroke
				(width 0.1)
				(type default)
			)
			(layer "B.Fab")
		)
		(fp_line
			(start -0.12065 -0.3048)
			(end -0.67945 -0.3048)
			(stroke
				(width 0.1)
				(type default)
			)
			(layer "B.Fab")
		)
		(fp_line
			(start 0.12065 -0.305054)
			(end 0.12065 -0.2794)
			(stroke
				(width 0.1)
				(type default)
			)
			(layer "B.Fab")
		)
		(fp_line
			(start 0.67945 -0.305054)
			(end 0.12065 -0.305054)
			(stroke
				(width 0.1)
				(type default)
			)
			(layer "B.Fab")
		)
		(pad "1" smd circle
			(at 0.40005 0 90)
			(size 0 0)
			(layers "B.Cu" "B.Mask" "B.Paste")
			(net "PVDDCR_CPU1_P0_VOS5")
		)
		(pad "2" smd circle
			(at -0.40005 0 90)
			(size 0 0)
			(layers "B.Cu" "B.Mask" "B.Paste")
			(net "PVDDCR_CPU1_P0")
		)
	)
	(footprint ""
		(layer "B.Cu")
		(at 142.893542 -385.58216 180)
		(property "Reference" "R879"
			(at 0 0 0)
			(layer "B.SilkS")
			(hide yes)
			(effects
				(font
					(size 1.27 1.27)
				)
				(justify mirror)
			)
		)
		(property "Value" ""
			(at 0 0 0)
			(layer "B.Fab")
			(effects
				(font
					(size 1.27 1.27)
				)
				(justify mirror)
			)
		)
		(duplicate_pad_numbers_are_jumpers no)
		(fp_line
			(start 0.32512 0.175006)
			(end 0.32512 -0.175006)
			(stroke
				(width 0.1)
				(type default)
			)
			(layer "B.Fab")
		)
		(fp_line
			(start 0.32512 -0.175006)
			(end -0.32512 -0.175006)
			(stroke
				(width 0.1)
				(type default)
			)
			(layer "B.Fab")
		)
		(fp_line
			(start -0.32512 0.175006)
			(end 0.32512 0.175006)
			(stroke
				(width 0.1)
				(type default)
			)
			(layer "B.Fab")
		)
		(fp_line
			(start -0.32512 -0.175006)
			(end -0.32512 0.175006)
			(stroke
				(width 0.1)
				(type default)
			)
			(layer "B.Fab")
		)
		(pad "1" smd rect
			(at 0.2667 0)
			(size 0.3048 0.381)
			(layers "B.Cu" "B.Mask" "B.Paste")
			(net "TEST0_RT_CPU1_P2")
		)
		(pad "2" smd rect
			(at -0.2667 0 180)
			(size 0.3048 0.381)
			(layers "B.Cu" "B.Mask" "B.Paste")
			(net "GND")
		)
	)
	(footprint ""
		(layer "B.Cu")
		(at 160.206182 -386.766562 90)
		(property "Reference" "C394"
			(at 0 0 90)
			(layer "B.SilkS")
			(hide yes)
			(effects
				(font
					(size 1.27 1.27)
				)
				(justify mirror)
			)
		)
		(property "Value" ""
			(at 0 0 90)
			(layer "B.Fab")
			(effects
				(font
					(size 1.27 1.27)
				)
				(justify mirror)
			)
		)
		(duplicate_pad_numbers_are_jumpers no)
		(fp_line
			(start 0.299974 -0.150114)
			(end -0.299974 -0.150114)
			(stroke
				(width 0.1)
				(type default)
			)
			(layer "B.Fab")
		)
		(fp_line
			(start -0.299974 -0.150114)
			(end -0.299974 0.150114)
			(stroke
				(width 0.1)
				(type default)
			)
			(layer "B.Fab")
		)
		(fp_line
			(start 0.299974 0.150114)
			(end 0.299974 -0.150114)
			(stroke
				(width 0.1)
				(type default)
			)
			(layer "B.Fab")
		)
		(fp_line
			(start -0.299974 0.150114)
			(end 0.299974 0.150114)
			(stroke
				(width 0.1)
				(type default)
			)
			(layer "B.Fab")
		)
		(pad "1" smd rect
			(at 0.2667 0 270)
			(size 0.3048 0.381)
			(layers "B.Cu" "B.Mask" "B.Paste")
			(net "P0V9_CPU1_RT2_2A_2D")
		)
		(pad "2" smd rect
			(at -0.2667 0 270)
			(size 0.3048 0.381)
			(layers "B.Cu" "B.Mask" "B.Paste")
			(net "GND")
		)
	)
	(footprint ""
		(layer "B.Cu")
		(at 348.151958 -265.045952)
		(property "Reference" "C2626"
			(at 0 0 0)
			(layer "B.SilkS")
			(hide yes)
			(effects
				(font
					(size 1.27 1.27)
				)
				(justify mirror)
			)
		)
		(property "Value" ""
			(at 0 0 0)
			(layer "B.Fab")
			(effects
				(font
					(size 1.27 1.27)
				)
				(justify mirror)
			)
		)
		(duplicate_pad_numbers_are_jumpers no)
		(fp_line
			(start -0.7874 -0.4064)
			(end -0.7874 0.4064)
			(stroke
				(width 0.1524)
				(type default)
			)
			(layer "B.SilkS")
		)
		(fp_line
			(start -0.7874 0.4064)
			(end 0.7874 0.4064)
			(stroke
				(width 0.1524)
				(type default)
			)
			(layer "B.SilkS")
		)
		(fp_line
			(start 0.7874 -0.4064)
			(end -0.7874 -0.4064)
			(stroke
				(width 0.1524)
				(type default)
			)
			(layer "B.SilkS")
		)
		(fp_line
			(start 0.7874 0.4064)
			(end 0.7874 -0.4064)
			(stroke
				(width 0.1524)
				(type default)
			)
			(layer "B.SilkS")
		)
		(fp_line
			(start -0.67945 -0.3048)
			(end -0.67945 0.3048)
			(stroke
				(width 0.1)
				(type default)
			)
			(layer "B.Fab")
		)
		(fp_line
			(start -0.67945 0.3048)
			(end -0.120396 0.3048)
			(stroke
				(width 0.1)
				(type default)
			)
			(layer "B.Fab")
		)
		(fp_line
			(start -0.12065 -0.3048)
			(end -0.67945 -0.3048)
			(stroke
				(width 0.1)
				(type default)
			)
			(layer "B.Fab")
		)
		(fp_line
			(start -0.12065 -0.2794)
			(end -0.12065 -0.3048)
			(stroke
				(width 0.1)
				(type default)
			)
			(layer "B.Fab")
		)
		(fp_line
			(start -0.120396 0.2794)
			(end 0.12065 0.2794)
			(stroke
				(width 0.1)
				(type default)
			)
			(layer "B.Fab")
		)
		(fp_line
			(start -0.120396 0.3048)
			(end -0.120396 0.2794)
			(stroke
				(width 0.1)
				(type default)
			)
			(layer "B.Fab")
		)
		(fp_line
			(start 0.12065 -0.305054)
			(end 0.12065 -0.2794)
			(stroke
				(width 0.1)
				(type default)
			)
			(layer "B.Fab")
		)
		(fp_line
			(start 0.12065 -0.2794)
			(end -0.12065 -0.2794)
			(stroke
				(width 0.1)
				(type default)
			)
			(layer "B.Fab")
		)
		(fp_line
			(start 0.12065 0.2794)
			(end 0.12065 0.3048)
			(stroke
				(width 0.1)
				(type default)
			)
			(layer "B.Fab")
		)
		(fp_line
			(start 0.12065 0.3048)
			(end 0.67945 0.3048)
			(stroke
				(width 0.1)
				(type default)
			)
			(layer "B.Fab")
		)
		(fp_line
			(start 0.67945 -0.305054)
			(end 0.12065 -0.305054)
			(stroke
				(width 0.1)
				(type default)
			)
			(layer "B.Fab")
		)
		(fp_line
			(start 0.67945 0.3048)
			(end 0.67945 -0.305054)
			(stroke
				(width 0.1)
				(type default)
			)
			(layer "B.Fab")
		)
		(pad "1" smd circle
			(at 0.40005 0 180)
			(size 0 0)
			(layers "B.Cu" "B.Mask" "B.Paste")
			(net "PVDDIO_P0")
		)
		(pad "2" smd circle
			(at -0.40005 0 180)
			(size 0 0)
			(layers "B.Cu" "B.Mask" "B.Paste")
			(net "GND")
		)
	)
	(footprint ""
		(layer "B.Cu")
		(at 438.013348 -19.07667 -90)
		(property "Reference" "R1896"
			(at 0 0 90)
			(layer "B.SilkS")
			(hide yes)
			(effects
				(font
					(size 1.27 1.27)
				)
				(justify mirror)
			)
		)
		(property "Value" ""
			(at 0 0 90)
			(layer "B.Fab")
			(effects
				(font
					(size 1.27 1.27)
				)
				(justify mirror)
			)
		)
		(duplicate_pad_numbers_are_jumpers no)
		(fp_line
			(start -0.7874 0.4064)
			(end 0.7874 0.4064)
			(stroke
				(width 0.1524)
				(type default)
			)
			(layer "B.SilkS")
		)
		(fp_line
			(start 0.7874 0.4064)
			(end 0.7874 -0.4064)
			(stroke
				(width 0.1524)
				(type default)
			)
			(layer "B.SilkS")
		)
		(fp_line
			(start -0.7874 -0.4064)
			(end -0.7874 0.4064)
			(stroke
				(width 0.1524)
				(type default)
			)
			(layer "B.SilkS")
		)
		(fp_line
			(start 0.7874 -0.4064)
			(end -0.7874 -0.4064)
			(stroke
				(width 0.1524)
				(type default)
			)
			(layer "B.SilkS")
		)
		(fp_line
			(start -0.67945 0.3048)
			(end -0.120396 0.3048)
			(stroke
				(width 0.1)
				(type default)
			)
			(layer "B.Fab")
		)
		(fp_line
			(start -0.120396 0.3048)
			(end -0.120396 0.2794)
			(stroke
				(width 0.1)
				(type default)
			)
			(layer "B.Fab")
		)
		(fp_line
			(start 0.12065 0.3048)
			(end 0.67945 0.3048)
			(stroke
				(width 0.1)
				(type default)
			)
			(layer "B.Fab")
		)
		(fp_line
			(start 0.67945 0.3048)
			(end 0.67945 -0.305054)
			(stroke
				(width 0.1)
				(type default)
			)
			(layer "B.Fab")
		)
		(fp_line
			(start -0.120396 0.2794)
			(end 0.12065 0.2794)
			(stroke
				(width 0.1)
				(type default)
			)
			(layer "B.Fab")
		)
		(fp_line
			(start 0.12065 0.2794)
			(end 0.12065 0.3048)
			(stroke
				(width 0.1)
				(type default)
			)
			(layer "B.Fab")
		)
		(fp_line
			(start -0.12065 -0.2794)
			(end -0.12065 -0.3048)
			(stroke
				(width 0.1)
				(type default)
			)
			(layer "B.Fab")
		)
		(fp_line
			(start 0.12065 -0.2794)
			(end -0.12065 -0.2794)
			(stroke
				(width 0.1)
				(type default)
			)
			(layer "B.Fab")
		)
		(fp_line
			(start -0.67945 -0.3048)
			(end -0.67945 0.3048)
			(stroke
				(width 0.1)
				(type default)
			)
			(layer "B.Fab")
		)
		(fp_line
			(start -0.12065 -0.3048)
			(end -0.67945 -0.3048)
			(stroke
				(width 0.1)
				(type default)
			)
			(layer "B.Fab")
		)
		(fp_line
			(start 0.12065 -0.305054)
			(end 0.12065 -0.2794)
			(stroke
				(width 0.1)
				(type default)
			)
			(layer "B.Fab")
		)
		(fp_line
			(start 0.67945 -0.305054)
			(end 0.12065 -0.305054)
			(stroke
				(width 0.1)
				(type default)
			)
			(layer "B.Fab")
		)
		(pad "1" smd circle
			(at 0.40005 0 90)
			(size 0 0)
			(layers "B.Cu" "B.Mask" "B.Paste")
			(net "OCP_SFF_ISO_BIF0_EN")
		)
		(pad "2" smd circle
			(at -0.40005 0 90)
			(size 0 0)
			(layers "B.Cu" "B.Mask" "B.Paste")
			(net "GND")
		)
	)
	(footprint ""
		(layer "B.Cu")
		(at 215.514428 -74.055986 180)
		(property "Reference" "R84"
			(at 0 0 0)
			(layer "B.SilkS")
			(hide yes)
			(effects
				(font
					(size 1.27 1.27)
				)
				(justify mirror)
			)
		)
		(property "Value" ""
			(at 0 0 0)
			(layer "B.Fab")
			(effects
				(font
					(size 1.27 1.27)
				)
				(justify mirror)
			)
		)
		(duplicate_pad_numbers_are_jumpers no)
		(fp_line
			(start 0.7874 0.4064)
			(end 0.7874 -0.4064)
			(stroke
				(width 0.1524)
				(type default)
			)
			(layer "B.SilkS")
		)
		(fp_line
			(start 0.7874 -0.4064)
			(end -0.7874 -0.4064)
			(stroke
				(width 0.1524)
				(type default)
			)
			(layer "B.SilkS")
		)
		(fp_line
			(start -0.7874 0.4064)
			(end 0.7874 0.4064)
			(stroke
				(width 0.1524)
				(type default)
			)
			(layer "B.SilkS")
		)
		(fp_line
			(start -0.7874 -0.4064)
			(end -0.7874 0.4064)
			(stroke
				(width 0.1524)
				(type default)
			)
			(layer "B.SilkS")
		)
		(fp_line
			(start 0.67945 0.3048)
			(end 0.67945 -0.305054)
			(stroke
				(width 0.1)
				(type default)
			)
			(layer "B.Fab")
		)
		(fp_line
			(start 0.67945 -0.305054)
			(end 0.12065 -0.305054)
			(stroke
				(width 0.1)
				(type default)
			)
			(layer "B.Fab")
		)
		(fp_line
			(start 0.12065 0.3048)
			(end 0.67945 0.3048)
			(stroke
				(width 0.1)
				(type default)
			)
			(layer "B.Fab")
		)
		(fp_line
			(start 0.12065 0.2794)
			(end 0.12065 0.3048)
			(stroke
				(width 0.1)
				(type default)
			)
			(layer "B.Fab")
		)
		(fp_line
			(start 0.12065 -0.2794)
			(end -0.12065 -0.2794)
			(stroke
				(width 0.1)
				(type default)
			)
			(layer "B.Fab")
		)
		(fp_line
			(start 0.12065 -0.305054)
			(end 0.12065 -0.2794)
			(stroke
				(width 0.1)
				(type default)
			)
			(layer "B.Fab")
		)
		(fp_line
			(start -0.120396 0.3048)
			(end -0.120396 0.2794)
			(stroke
				(width 0.1)
				(type default)
			)
			(layer "B.Fab")
		)
		(fp_line
			(start -0.120396 0.2794)
			(end 0.12065 0.2794)
			(stroke
				(width 0.1)
				(type default)
			)
			(layer "B.Fab")
		)
		(fp_line
			(start -0.12065 -0.2794)
			(end -0.12065 -0.3048)
			(stroke
				(width 0.1)
				(type default)
			)
			(layer "B.Fab")
		)
		(fp_line
			(start -0.12065 -0.3048)
			(end -0.67945 -0.3048)
			(stroke
				(width 0.1)
				(type default)
			)
			(layer "B.Fab")
		)
		(fp_line
			(start -0.67945 0.3048)
			(end -0.120396 0.3048)
			(stroke
				(width 0.1)
				(type default)
			)
			(layer "B.Fab")
		)
		(fp_line
			(start -0.67945 -0.3048)
			(end -0.67945 0.3048)
			(stroke
				(width 0.1)
				(type default)
			)
			(layer "B.Fab")
		)
		(pad "1" smd circle
			(at 0.40005 0)
			(size 0 0)
			(layers "B.Cu" "B.Mask" "B.Paste")
			(net "RMII_BMC_OCP_TXD_1")
		)
		(pad "2" smd circle
			(at -0.40005 0)
			(size 0 0)
			(layers "B.Cu" "B.Mask" "B.Paste")
			(net "GND")
		)
	)
)
